# SCM (Grand Teton) — schematic netlist excerpt (pin names and nets, part order shuffled) for the footprints in the layout excerpt that follows; sources: Cadence DE-HDL packaged netlist, KiCad conversion of 12092022_DA0F0TMDCD0_F0T_Management_Board_D_brd_V3_OCP.brd

R236  Q_RES  33.2 1% CHIP  pkg 0402LF  page 12 : A = SMB_BMC_MM15_SDA ; B = SMB_BMC_MM15_R_SDA
R209  Q_RES  10K 1% EMPTY  pkg 0402LF  page 15 : A = PECI_BMC ; B = GND

(kicad_pcb
	(version 20260206)
	(generator "pcbnew")
	(generator_version "10.0")
	(general
		(thickness 1.6)
		(legacy_teardrops no)
	)
	(paper "A4")
	(title_block
		(title "12092022_DA0F0TMDCD0_F0T_Management_Board_D_brd_V3_OCP.brd")
		(comment 1 "Grand Teton / footprints 43-44 of 1440")
	)
	(layers
		(0 "F.Cu" signal "TOP")
		(4 "In1.Cu" signal "GND")
		(6 "In2.Cu" signal "IN1")
		(8 "In3.Cu" signal "GND1")
		(10 "In4.Cu" signal "IN2")
		(12 "In5.Cu" signal "VCC")
		(14 "In6.Cu" signal "VCC1")
		(16 "In7.Cu" signal "IN3")
		(18 "In8.Cu" signal "GND2")
		(20 "In9.Cu" signal "IN4")
		(22 "In10.Cu" signal "GND3")
		(2 "B.Cu" signal "BOTTOM")
		(9 "F.Adhes" user "F.Adhesive")
		(11 "B.Adhes" user "B.Adhesive")
		(13 "F.Paste" user "Package Geometry/Pastemask Top")
		(15 "B.Paste" user "Package Geometry/Pastemask Bottom")
		(5 "F.SilkS" user "Ref Des/Silkscreen Top")
		(7 "B.SilkS" user "Ref Des/Silkscreen Bottom")
		(1 "F.Mask" user "Board Geometry/Soldermask Top")
		(3 "B.Mask" user "Board Geometry/Soldermask Bottom")
		(17 "Dwgs.User" user "User.Drawings")
		(19 "Cmts.User" user "User.Comments")
		(21 "Eco1.User" user "User.Eco1")
		(23 "Eco2.User" user "User.Eco2")
		(25 "Edge.Cuts" user "Board Geometry/Outline")
		(27 "Margin" user)
		(31 "F.CrtYd" user "Package Geometry/Place Bound Top")
		(29 "B.CrtYd" user "Package Geometry/Place Bound Bottom")
		(35 "F.Fab" user "Ref Des/Assembly Top")
		(33 "B.Fab" user "Ref Des/Assembly Bottom")
	)
	(footprint ""
		(layer "F.Cu")
		(at 49.657 -67.26174 180)
		(property "Reference" "R209"
			(at 0 0 180)
			(layer "F.SilkS")
			(hide yes)
			(effects
				(font
					(size 1.27 1.27)
				)
			)
		)
		(property "Value" ""
			(at 0 0 180)
			(layer "F.Fab")
			(effects
				(font
					(size 1.27 1.27)
				)
			)
		)
		(duplicate_pad_numbers_are_jumpers no)
		(fp_line
			(start 0.7874 0.4064)
			(end -0.7874 0.4064)
			(stroke
				(width 0.1524)
				(type default)
			)
			(layer "F.SilkS")
		)
		(fp_line
			(start 0.7874 -0.4064)
			(end 0.7874 0.4064)
			(stroke
				(width 0.1524)
				(type default)
			)
			(layer "F.SilkS")
		)
		(fp_line
			(start -0.7874 0.4064)
			(end -0.7874 -0.4064)
			(stroke
				(width 0.1524)
				(type default)
			)
			(layer "F.SilkS")
		)
		(fp_line
			(start -0.7874 -0.4064)
			(end 0.7874 -0.4064)
			(stroke
				(width 0.1524)
				(type default)
			)
			(layer "F.SilkS")
		)
		(fp_line
			(start 0.67945 0.3048)
			(end 0.120396 0.3048)
			(stroke
				(width 0.1)
				(type default)
			)
			(layer "F.Fab")
		)
		(fp_line
			(start 0.67945 -0.3048)
			(end 0.67945 0.3048)
			(stroke
				(width 0.1)
				(type default)
			)
			(layer "F.Fab")
		)
		(fp_line
			(start 0.12065 -0.2794)
			(end 0.12065 -0.3048)
			(stroke
				(width 0.1)
				(type default)
			)
			(layer "F.Fab")
		)
		(fp_line
			(start 0.12065 -0.3048)
			(end 0.67945 -0.3048)
			(stroke
				(width 0.1)
				(type default)
			)
			(layer "F.Fab")
		)
		(fp_line
			(start 0.120396 0.3048)
			(end 0.120396 0.2794)
			(stroke
				(width 0.1)
				(type default)
			)
			(layer "F.Fab")
		)
		(fp_line
			(start 0.120396 0.2794)
			(end -0.12065 0.2794)
			(stroke
				(width 0.1)
				(type default)
			)
			(layer "F.Fab")
		)
		(fp_line
			(start -0.12065 0.3048)
			(end -0.67945 0.3048)
			(stroke
				(width 0.1)
				(type default)
			)
			(layer "F.Fab")
		)
		(fp_line
			(start -0.12065 0.2794)
			(end -0.12065 0.3048)
			(stroke
				(width 0.1)
				(type default)
			)
			(layer "F.Fab")
		)
		(fp_line
			(start -0.12065 -0.2794)
			(end 0.12065 -0.2794)
			(stroke
				(width 0.1)
				(type default)
			)
			(layer "F.Fab")
		)
		(fp_line
			(start -0.12065 -0.305054)
			(end -0.12065 -0.2794)
			(stroke
				(width 0.1)
				(type default)
			)
			(layer "F.Fab")
		)
		(fp_line
			(start -0.67945 0.3048)
			(end -0.67945 -0.305054)
			(stroke
				(width 0.1)
				(type default)
			)
			(layer "F.Fab")
		)
		(fp_line
			(start -0.67945 -0.305054)
			(end -0.12065 -0.305054)
			(stroke
				(width 0.1)
				(type default)
			)
			(layer "F.Fab")
		)
		(pad "1" smd circle
			(at -0.40005 0 180)
			(size 0 0)
			(layers "F.Cu" "F.Mask" "F.Paste")
			(net "PECI_BMC")
		)
		(pad "2" smd circle
			(at 0.40005 0 180)
			(size 0 0)
			(layers "F.Cu" "F.Mask" "F.Paste")
			(net "GND")
		)
	)
	(footprint ""
		(layer "F.Cu")
		(at 51.84648 -34.637726 90)
		(property "Reference" "R236"
			(at 0 0 90)
			(layer "F.SilkS")
			(hide yes)
			(effects
				(font
					(size 1.27 1.27)
				)
			)
		)
		(property "Value" ""
			(at 0 0 90)
			(layer "F.Fab")
			(effects
				(font
					(size 1.27 1.27)
				)
			)
		)
		(duplicate_pad_numbers_are_jumpers no)
		(fp_line
			(start 0.7874 -0.4064)
			(end 0.7874 0.4064)
			(stroke
				(width 0.1524)
				(type default)
			)
			(layer "F.SilkS")
		)
		(fp_line
			(start -0.7874 -0.4064)
			(end 0.7874 -0.4064)
			(stroke
				(width 0.1524)
				(type default)
			)
			(layer "F.SilkS")
		)
		(fp_line
			(start 0.7874 0.4064)
			(end -0.7874 0.4064)
			(stroke
				(width 0.1524)
				(type default)
			)
			(layer "F.SilkS")
		)
		(fp_line
			(start -0.7874 0.4064)
			(end -0.7874 -0.4064)
			(stroke
				(width 0.1524)
				(type default)
			)
			(layer "F.SilkS")
		)
		(fp_line
			(start -0.12065 -0.305054)
			(end -0.12065 -0.2794)
			(stroke
				(width 0.1)
				(type default)
			)
			(layer "F.Fab")
		)
		(fp_line
			(start -0.67945 -0.305054)
			(end -0.12065 -0.305054)
			(stroke
				(width 0.1)
				(type default)
			)
			(layer "F.Fab")
		)
		(fp_line
			(start 0.67945 -0.3048)
			(end 0.67945 0.3048)
			(stroke
				(width 0.1)
				(type default)
			)
			(layer "F.Fab")
		)
		(fp_line
			(start 0.12065 -0.3048)
			(end 0.67945 -0.3048)
			(stroke
				(width 0.1)
				(type default)
			)
			(layer "F.Fab")
		)
		(fp_line
			(start 0.12065 -0.2794)
			(end 0.12065 -0.3048)
			(stroke
				(width 0.1)
				(type default)
			)
			(layer "F.Fab")
		)
		(fp_line
			(start -0.12065 -0.2794)
			(end 0.12065 -0.2794)
			(stroke
				(width 0.1)
				(type default)
			)
			(layer "F.Fab")
		)
		(fp_line
			(start 0.120396 0.2794)
			(end -0.12065 0.2794)
			(stroke
				(width 0.1)
				(type default)
			)
			(layer "F.Fab")
		)
		(fp_line
			(start -0.12065 0.2794)
			(end -0.12065 0.3048)
			(stroke
				(width 0.1)
				(type default)
			)
			(layer "F.Fab")
		)
		(fp_line
			(start 0.67945 0.3048)
			(end 0.120396 0.3048)
			(stroke
				(width 0.1)
				(type default)
			)
			(layer "F.Fab")
		)
		(fp_line
			(start 0.120396 0.3048)
			(end 0.120396 0.2794)
			(stroke
				(width 0.1)
				(type default)
			)
			(layer "F.Fab")
		)
		(fp_line
			(start -0.12065 0.3048)
			(end -0.67945 0.3048)
			(stroke
				(width 0.1)
				(type default)
			)
			(layer "F.Fab")
		)
		(fp_line
			(start -0.67945 0.3048)
			(end -0.67945 -0.305054)
			(stroke
				(width 0.1)
				(type default)
			)
			(layer "F.Fab")
		)
		(pad "1" smd circle
			(at -0.40005 0 90)
			(size 0 0)
			(layers "F.Cu" "F.Mask" "F.Paste")
			(net "SMB_BMC_MM15_SDA")
		)
		(pad "2" smd circle
			(at 0.40005 0 90)
			(size 0 0)
			(layers "F.Cu" "F.Mask" "F.Paste")
			(net "SMB_BMC_MM15_R_SDA")
		)
	)
)
